# T6G (Grand Teton) — schematic netlist excerpt (pin names and nets, part order shuffled) for the footprints in the layout excerpt that follows; sources: Cadence DE-HDL packaged netlist, KiCad conversion of 04192023_DAF0TMB3IC0_F0TG_MB_C_brd_V02_OCP.brd

J16  SCONN288_DDR506112002KQ  IO  pkg DDR288S_1-1VXC  page 92
  VIN_BULK0  = P12V_MEM_CPU0
  RFU0  = NC
  VIN_MGMT  = P3V3_AUX
  HSCL  = I3C_SPD_DDRG_CPU0_SCL
  HSDA  = I3C_SPD_DDRG_CPU0_SDA
  VSS0  = GND
  DQ0_A  = M_G_CPU0_SA_DQ<0>
  VSS1  = GND
  DQ1_A  = M_G_CPU0_SA_DQ<1>
  VSS2  = GND
  DQS0_A_T  = M_G_CPU0_SA_DQS_DP<0>
  DQS0_A_C  = M_G_CPU0_SA_DQS_DN<0>
  VSS3  = GND
  DQ4_A  = M_G_CPU0_SA_DQ<4>
  VSS4  = GND
  DQ5_A  = M_G_CPU0_SA_DQ<5>
  VSS5  = GND
  DQ8_A  = M_G_CPU0_SA_DQ<8>
  VSS6  = GND
  DQ9_A  = M_G_CPU0_SA_DQ<9>
  VSS7  = GND
  DQS1_A_T  = M_G_CPU0_SA_DQS_DP<1>
  DQS1_A_C  = M_G_CPU0_SA_DQS_DN<1>
  VSS8  = GND
  DQ12_A  = M_G_CPU0_SA_DQ<12>
  VSS9  = GND
  DQ13_A  = M_G_CPU0_SA_DQ<13>
  VSS10  = GND
  DQ16_A  = M_G_CPU0_SA_DQ<16>
  VSS11  = GND
  DQ17_A  = M_G_CPU0_SA_DQ<17>
  VSS12  = GND
  DQS2_A_T  = M_G_CPU0_SA_DQS_DP<2>
  DQS2_A_C  = M_G_CPU0_SA_DQS_DN<2>
  VSS13  = GND
  DQ20_A  = M_G_CPU0_SA_DQ<20>
  VSS14  = GND
  DQ21_A  = M_G_CPU0_SA_DQ<21>
  VSS15  = GND
  DQ24_A  = M_G_CPU0_SA_DQ<24>
  VSS16  = GND
  DQ25_A  = M_G_CPU0_SA_DQ<25>
  VSS17  = GND
  DQS3_A_T  = M_G_CPU0_SA_DQS_DP<3>
  DQS3_A_C  = M_G_CPU0_SA_DQS_DN<3>
  VSS18  = GND
  DQ28_A  = M_G_CPU0_SA_DQ<28>
  VSS19  = GND
  DQ29_A  = M_G_CPU0_SA_DQ<29>
  VSS20  = GND
  CB0_A  = M_G_CPU0_SA_CB<0>
  VSS21  = GND
  CB1_A  = M_G_CPU0_SA_CB<1>
  VSS22  = GND
  DQS4_A_T  = M_G_CPU0_SA_DQS_DP<4>
  DQS4_A_C  = M_G_CPU0_SA_DQS_DN<4>
  VSS23  = GND
  CB4_A  = M_G_CPU0_SA_CB<4>
  VSS24  = GND
  CB5_A  = M_G_CPU0_SA_CB<5>
  VSS25  = GND
  ALERT_N  = M_G_CPU0_ALERT_N
  VSS26  = GND
  CS0_A_N  = M_G_CPU0_SA_CS_N<0>
  VSS27  = GND
  CA0_A  = M_G_CPU0_SA_CA<0>
  VSS28  = GND
  CA2_A  = M_G_CPU0_SA_CA<2>
  VSS29  = GND
  CA4_A  = M_G_CPU0_SA_CA<4>
  VSS30  = GND
  CA6_A  = M_G_CPU0_SA_CA<6>
  VSS31  = GND
  PAR_A  = M_G_CPU0_SA_PAR
  VSS32  = GND
  CA0_B  = M_G_CPU0_SB_CA<0>
  VSS33  = GND
  CA2_B  = M_G_CPU0_SB_CA<2>
  VSS34  = GND
  CA4_B  = M_G_CPU0_SB_CA<4>
  VSS35  = GND
  CA6_B  = M_G_CPU0_SB_CA<6>
  VSS36  = GND
  CS0_B_N  = M_G_CPU0_SB_CS_N<0>
  VSS37  = GND
  \lbd||rsp_a_n\  = M_G_CPU0_SA_RSP<0>
  \lbs||rsp_b_n\  = M_G_CPU0_SB_RSP<0>
  VSS38  = GND
  CB4_B  = M_G_CPU0_SB_CB<4>
  VSS39  = GND
  CB5_B  = M_G_CPU0_SB_CB<5>
  VSS40  = GND
  \dqs9_b_t||tdqs9_b_t||dbi4_b_n\  = M_G_CPU0_SB_DQS_DP<9>
  \dqs9_b_c||tdqs9_b_c\  = M_G_CPU0_SB_DQS_DN<9>
  VSS41  = GND
  CB0_B  = M_G_CPU0_SB_CB<0>
  VSS42  = GND
  CB1_B  = M_G_CPU0_SB_CB<1>
  VSS43  = GND
  DQ0_B  = M_G_CPU0_SB_DQ<0>
  VSS44  = GND
  DQ1_B  = M_G_CPU0_SB_DQ<1>
  VSS45  = GND
  DQS0_B_T  = M_G_CPU0_SB_DQS_DP<0>
  DQS0_B_C  = M_G_CPU0_SB_DQS_DN<0>
  VSS46  = GND
  DQ4_B  = M_G_CPU0_SB_DQ<4>
  VSS47  = GND
  DQ5_B  = M_G_CPU0_SB_DQ<5>
  VSS48  = GND
  DQ8_B  = M_G_CPU0_SB_DQ<8>
  VSS49  = GND
  DQ9_B  = M_G_CPU0_SB_DQ<9>
  VSS50  = GND
  DQS1_B_T  = M_G_CPU0_SB_DQS_DP<1>
  DQS1_B_C  = M_G_CPU0_SB_DQS_DN<1>
  VSS51  = GND
  DQ12_B  = M_G_CPU0_SB_DQ<12>
  VSS52  = GND
  DQ13_B  = M_G_CPU0_SB_DQ<13>
  VSS53  = GND
  DQ16_B  = M_G_CPU0_SB_DQ<16>
  VSS54  = GND
  DQ17_B  = M_G_CPU0_SB_DQ<17>
  VSS55  = GND
  DQS2_B_T  = M_G_CPU0_SB_DQS_DP<2>
  DQS2_B_C  = M_G_CPU0_SB_DQS_DN<2>
  VSS56  = GND
  DQ20_B  = M_G_CPU0_SB_DQ<20>
  VSS57  = GND
  DQ21_B  = M_G_CPU0_SB_DQ<21>
  VSS58  = GND
  DQ24_B  = M_G_CPU0_SB_DQ<24>
  VSS59  = GND
  DQ25_B  = M_G_CPU0_SB_DQ<25>
  VSS60  = GND
  DQS3_B_T  = M_G_CPU0_SB_DQS_DP<3>
  DQS3_B_C  = M_G_CPU0_SB_DQS_DN<3>
  VSS61  = GND
  DQ28_B  = M_G_CPU0_SB_DQ<28>
  VSS62  = GND
  DQ29_B  = M_G_CPU0_SB_DQ<29>
  VSS63  = GND
  RFU1  = NC
  VIN_BULK1  = P12V_MEM_CPU0
  VIN_BULK2  = P12V_MEM_CPU0
  \pwr_good||fail_n\  = PWRGD_CHG_CPU0_DIMM0
  HAS  = PD_CHG_CPU0_DIMM0_SAA
  RFU2  = NC
  RFU3  = NC
  VSS64  = GND
  DQ2_A  = M_G_CPU0_SA_DQ<2>
  VSS65  = GND
  DQ3_A  = M_G_CPU0_SA_DQ<3>
  VSS66  = GND
  \dqs5_a_c||tdqs5_a_c||dqs5_a_t||tdqs5_a_t\  = M_G_CPU0_SA_DQS_DN<5>
  \dqs5_a_t||tdqs5_a_t\  = M_G_CPU0_SA_DQS_DP<5>
  VSS67  = GND
  DQ6_A  = M_G_CPU0_SA_DQ<6>
  VSS68  = GND
  DQ7_A  = M_G_CPU0_SA_DQ<7>
  VSS69  = GND
  DQ10_A  = M_G_CPU0_SA_DQ<10>
  VSS70  = GND
  DQ11_A  = M_G_CPU0_SA_DQ<11>
  VSS71  = GND
  \dqs6_a_c||tdqs6_a_c||dqs6_a_t||tdqs6_a_t\  = M_G_CPU0_SA_DQS_DN<6>
  \dqs6_a_t||tdqs6_a_t\  = M_G_CPU0_SA_DQS_DP<6>
  VSS72  = GND
  DQ14_A  = M_G_CPU0_SA_DQ<14>
  VSS73  = GND
  DQ15_A  = M_G_CPU0_SA_DQ<15>
  VSS74  = GND
  DQ18_A  = M_G_CPU0_SA_DQ<18>
  VSS75  = GND
  DQ19_A  = M_G_CPU0_SA_DQ<19>
  VSS76  = GND
  \dqs7_a_c||tdqs7_a_c\  = M_G_CPU0_SA_DQS_DN<7>
  \dqs7_a_t||tdqs7_a_t\  = M_G_CPU0_SA_DQS_DP<7>
  VSS77  = GND
  DQ22_A  = M_G_CPU0_SA_DQ<22>
  VSS78  = GND
  DQ23_A  = M_G_CPU0_SA_DQ<23>
  VSS79  = GND
  DQ26_A  = M_G_CPU0_SA_DQ<26>
  VSS80  = GND
  DQ27_A  = M_G_CPU0_SA_DQ<27>
  VSS81  = GND
  \dqs8_a_c||tdqs8_a_c\  = M_G_CPU0_SA_DQS_DN<8>
  \dqs8_a_t||tdqs8_a_t\  = M_G_CPU0_SA_DQS_DP<8>
  VSS82  = GND
  DQ30_A  = M_G_CPU0_SA_DQ<30>
  VSS83  = GND
  DQ31_A  = M_G_CPU0_SA_DQ<31>
  VSS84  = GND
  CB2_A  = M_G_CPU0_SA_CB<2>
  VSS85  = GND
  CB3_A  = M_G_CPU0_SA_CB<3>
  VSS86  = GND
  \dqs9_a_c||tdqs9_a_c\  = M_G_CPU0_SA_DQS_DN<9>
  \dqs9_a_t||tdqs9_a_t\  = M_G_CPU0_SA_DQS_DP<9>
  VSS87  = GND
  CB6_A  = M_G_CPU0_SA_CB<6>
  VSS88  = GND
  CB7_A  = M_G_CPU0_SA_CB<7>
  VSS89  = GND
  RESET_N  = M_G_CPU0_RESET_N
  VSS90  = GND
  CS1_A_N  = M_G_CPU0_SA_CS_N<1>
  VSS91  = GND
  CA1_A  = M_G_CPU0_SA_CA<1>
  VSS92  = GND
  CA3_A  = M_G_CPU0_SA_CA<3>
  VSS93  = GND
  CA5_A  = M_G_CPU0_SA_CA<5>
  VSS94  = GND
  CK_T  = M_G_CPU0_CLK_DP<0>
  CK_C  = M_G_CPU0_CLK_DN<0>
  VSS95  = GND
  RFU4  = NC
  CA1_B  = M_G_CPU0_SB_CA<1>
  VSS96  = GND
  CA3_B  = M_G_CPU0_SB_CA<3>
  VSS97  = GND
  CA5_B  = M_G_CPU0_SB_CA<5>
  VSS98  = GND
  PAR_B  = M_G_CPU0_SB_PAR
  VSS99  = GND
  CS1_B_N  = M_G_CPU0_SB_CS_N<1>
  VSS100  = GND
  RFU5  = NC
  RFU6  = NC
  VSS101  = GND
  CB6_B  = M_G_CPU0_SB_CB<6>
  VSS102  = GND
  CB7_B  = M_G_CPU0_SB_CB<7>
  VSS103  = GND
  DQS4_B_C  = M_G_CPU0_SB_DQS_DN<4>
  DQS4_B_T  = M_G_CPU0_SB_DQS_DP<4>
  VSS104  = GND
  CB2_B  = M_G_CPU0_SB_CB<2>
  VSS105  = GND
  CB3_B  = M_G_CPU0_SB_CB<3>
  VSS106  = GND
  DQ2_B  = M_G_CPU0_SB_DQ<2>
  VSS107  = GND
  DQ3_B  = M_G_CPU0_SB_DQ<3>
  VSS108  = GND
  \dqs5_b_c||tdqs5_b_c\  = M_G_CPU0_SB_DQS_DN<5>
  \dqs5_b_t||tdqs5_b_t\  = M_G_CPU0_SB_DQS_DP<5>
  VSS109  = GND
  DQ6_B  = M_G_CPU0_SB_DQ<6>
  VSS110  = GND
  DQ7_B  = M_G_CPU0_SB_DQ<7>
  VSS111  = GND
  DQ10_B  = M_G_CPU0_SB_DQ<10>
  VSS112  = GND
  DQ11_B  = M_G_CPU0_SB_DQ<11>
  VSS113  = GND
  \dqs6_b_c||tdqs6_b_c\  = M_G_CPU0_SB_DQS_DN<6>
  \dqs6_b_t||tdqs6_b_t\  = M_G_CPU0_SB_DQS_DP<6>
  VSS114  = GND
  DQ14_B  = M_G_CPU0_SB_DQ<14>
  VSS115  = GND
  DQ15_B  = M_G_CPU0_SB_DQ<15>
  VSS116  = GND
  DQ18_B  = M_G_CPU0_SB_DQ<18>
  VSS117  = GND
  DQ19_B  = M_G_CPU0_SB_DQ<19>
  VSS118  = GND
  \dqs7_b_c||tdqs7_b_c\  = M_G_CPU0_SB_DQS_DN<7>
  \dqs7_b_t||tdqs7_b_t\  = M_G_CPU0_SB_DQS_DP<7>
  VSS119  = GND
  DQ22_B  = M_G_CPU0_SB_DQ<22>
  VSS120  = GND
  DQ23_B  = M_G_CPU0_SB_DQ<23>
  VSS121  = GND
  DQ26_B  = M_G_CPU0_SB_DQ<26>
  VSS122  = GND
  DQ27_B  = M_G_CPU0_SB_DQ<27>
  VSS123  = GND
  \dqs8_b_c||tdqs8_b_c\  = M_G_CPU0_SB_DQS_DN<8>
  \dqs8_b_t||tdqs8_b_t\  = M_G_CPU0_SB_DQS_DP<8>
  VSS124  = GND
  DQ30_B  = M_G_CPU0_SB_DQ<30>
  VSS125  = GND
  DQ31_B  = M_G_CPU0_SB_DQ<31>
  VSS126  = GND
  G1  = GND
  G2  = GND
  G3  = GND

(kicad_pcb
	(version 20260206)
	(generator "pcbnew")
	(generator_version "10.0")
	(general
		(thickness 1.6)
		(legacy_teardrops no)
	)
	(paper "A4")
	(title_block
		(title "04192023_DAF0TMB3IC0_F0TG_MB_C_brd_V02_OCP.brd")
		(comment 1 "Grand Teton / footprint 1808 of 8354 (J16), pads 185-230 of 291")
	)
	(layers
		(0 "F.Cu" signal "TOP")
		(4 "In1.Cu" signal "GND")
		(6 "In2.Cu" signal "IN1")
		(8 "In3.Cu" signal "GND1")
		(10 "In4.Cu" signal "IN2")
		(12 "In5.Cu" signal "GND2")
		(14 "In6.Cu" signal "IN3")
		(16 "In7.Cu" signal "GND3")
		(18 "In8.Cu" signal "VCC")
		(20 "In9.Cu" signal "VCC1")
		(22 "In10.Cu" signal "GND4")
		(24 "In11.Cu" signal "IN4")
		(26 "In12.Cu" signal "GND5")
		(28 "In13.Cu" signal "IN5")
		(30 "In14.Cu" signal "GND6")
		(32 "In15.Cu" signal "IN6")
		(34 "In16.Cu" signal "GND7")
		(2 "B.Cu" signal "BOTTOM")
		(9 "F.Adhes" user "F.Adhesive")
		(11 "B.Adhes" user "B.Adhesive")
		(13 "F.Paste" user "Package Geometry/Pastemask Top")
		(15 "B.Paste" user "Package Geometry/Pastemask Bottom")
		(5 "F.SilkS" user "Ref Des/Silkscreen Top")
		(7 "B.SilkS" user "Ref Des/Silkscreen Bottom")
		(1 "F.Mask" user "Board Geometry/Soldermask Top")
		(3 "B.Mask" user "Board Geometry/Soldermask Bottom")
		(17 "Dwgs.User" user "User.Drawings")
		(19 "Cmts.User" user "User.Comments")
		(21 "Eco1.User" user "User.Eco1")
		(23 "Eco2.User" user "User.Eco2")
		(25 "Edge.Cuts" user "Board Geometry/Outline")
		(27 "Margin" user)
		(31 "F.CrtYd" user "Package Geometry/Place Bound Top")
		(29 "B.CrtYd" user "Package Geometry/Place Bound Bottom")
		(35 "F.Fab" user "Ref Des/Assembly Top")
		(33 "B.Fab" user "Ref Des/Assembly Bottom")
	)
	(footprint ""
		(layer "F.Cu")
		(at 414.418018 -255.560068 180)
		(property "Reference" "J16"
			(at 1.474216 81.889092 0)
			(unlocked yes)
			(layer "F.SilkS")
			(effects
				(font
					(size 0.7874 0.5842)
					(thickness 0.1524)
				)
			)
		)
		(property "Value" ""
			(at 0 0 180)
			(layer "F.Fab")
			(effects
				(font
					(size 1.27 1.27)
				)
			)
		)
		(duplicate_pad_numbers_are_jumpers no)
		(pad "185" smd rect
			(at 2.050034 -29.325062 90)
			(size 0.519938 1.4986)
			(layers "F.Cu" "F.Mask" "F.Paste")
			(net "M_G_CPU0_SA_DQ<26>")
		)
		(pad "186" smd rect
			(at 2.050034 -28.474924 90)
			(size 0.519938 1.4986)
			(layers "F.Cu" "F.Mask" "F.Paste")
			(net "GND")
		)
		(pad "187" smd rect
			(at 2.050034 -27.62504 90)
			(size 0.519938 1.4986)
			(layers "F.Cu" "F.Mask" "F.Paste")
			(net "M_G_CPU0_SA_DQ<27>")
		)
		(pad "188" smd rect
			(at 2.050034 -26.774902 90)
			(size 0.519938 1.4986)
			(layers "F.Cu" "F.Mask" "F.Paste")
			(net "GND")
		)
		(pad "189" smd rect
			(at 2.050034 -25.925018 90)
			(size 0.519938 1.4986)
			(layers "F.Cu" "F.Mask" "F.Paste")
			(net "M_G_CPU0_SA_DQS_DN<8>")
		)
		(pad "190" smd rect
			(at 2.050034 -25.07488 90)
			(size 0.519938 1.4986)
			(layers "F.Cu" "F.Mask" "F.Paste")
			(net "M_G_CPU0_SA_DQS_DP<8>")
		)
		(pad "191" smd rect
			(at 2.050034 -24.224996 90)
			(size 0.519938 1.4986)
			(layers "F.Cu" "F.Mask" "F.Paste")
			(net "GND")
		)
		(pad "192" smd rect
			(at 2.050034 -23.375112 90)
			(size 0.519938 1.4986)
			(layers "F.Cu" "F.Mask" "F.Paste")
			(net "M_G_CPU0_SA_DQ<30>")
		)
		(pad "193" smd rect
			(at 2.050034 -22.524974 90)
			(size 0.519938 1.4986)
			(layers "F.Cu" "F.Mask" "F.Paste")
			(net "GND")
		)
		(pad "194" smd rect
			(at 2.050034 -21.67509 90)
			(size 0.519938 1.4986)
			(layers "F.Cu" "F.Mask" "F.Paste")
			(net "M_G_CPU0_SA_DQ<31>")
		)
		(pad "195" smd rect
			(at 2.050034 -20.824952 90)
			(size 0.519938 1.4986)
			(layers "F.Cu" "F.Mask" "F.Paste")
			(net "GND")
		)
		(pad "196" smd rect
			(at 2.050034 -19.975068 90)
			(size 0.519938 1.4986)
			(layers "F.Cu" "F.Mask" "F.Paste")
			(net "M_G_CPU0_SA_CB<2>")
		)
		(pad "197" smd rect
			(at 2.050034 -19.12493 90)
			(size 0.519938 1.4986)
			(layers "F.Cu" "F.Mask" "F.Paste")
			(net "GND")
		)
		(pad "198" smd rect
			(at 2.050034 -18.275046 90)
			(size 0.519938 1.4986)
			(layers "F.Cu" "F.Mask" "F.Paste")
			(net "M_G_CPU0_SA_CB<3>")
		)
		(pad "199" smd rect
			(at 2.050034 -17.424908 90)
			(size 0.519938 1.4986)
			(layers "F.Cu" "F.Mask" "F.Paste")
			(net "GND")
		)
		(pad "200" smd rect
			(at 2.050034 -16.575024 90)
			(size 0.519938 1.4986)
			(layers "F.Cu" "F.Mask" "F.Paste")
			(net "M_G_CPU0_SA_DQS_DN<9>")
		)
		(pad "201" smd rect
			(at 2.050034 -15.724886 90)
			(size 0.519938 1.4986)
			(layers "F.Cu" "F.Mask" "F.Paste")
			(net "M_G_CPU0_SA_DQS_DP<9>")
		)
		(pad "202" smd rect
			(at 2.050034 -14.875002 90)
			(size 0.519938 1.4986)
			(layers "F.Cu" "F.Mask" "F.Paste")
			(net "GND")
		)
		(pad "203" smd rect
			(at 2.050034 -14.025118 90)
			(size 0.519938 1.4986)
			(layers "F.Cu" "F.Mask" "F.Paste")
			(net "M_G_CPU0_SA_CB<6>")
		)
		(pad "204" smd rect
			(at 2.050034 -13.17498 90)
			(size 0.519938 1.4986)
			(layers "F.Cu" "F.Mask" "F.Paste")
			(net "GND")
		)
		(pad "205" smd rect
			(at 2.050034 -12.325096 90)
			(size 0.519938 1.4986)
			(layers "F.Cu" "F.Mask" "F.Paste")
			(net "M_G_CPU0_SA_CB<7>")
		)
		(pad "206" smd rect
			(at 2.050034 -11.474958 90)
			(size 0.519938 1.4986)
			(layers "F.Cu" "F.Mask" "F.Paste")
			(net "GND")
		)
		(pad "207" smd rect
			(at 2.050034 -10.625074 90)
			(size 0.519938 1.4986)
			(layers "F.Cu" "F.Mask" "F.Paste")
			(net "M_G_CPU0_RESET_N")
		)
		(pad "208" smd rect
			(at 2.050034 -9.774936 90)
			(size 0.519938 1.4986)
			(layers "F.Cu" "F.Mask" "F.Paste")
			(net "GND")
		)
		(pad "209" smd rect
			(at 2.050034 -8.925052 90)
			(size 0.519938 1.4986)
			(layers "F.Cu" "F.Mask" "F.Paste")
			(net "M_G_CPU0_SA_CS_N<1>")
		)
		(pad "210" smd rect
			(at 2.050034 -8.074914 90)
			(size 0.519938 1.4986)
			(layers "F.Cu" "F.Mask" "F.Paste")
			(net "GND")
		)
		(pad "211" smd rect
			(at 2.050034 -7.22503 90)
			(size 0.519938 1.4986)
			(layers "F.Cu" "F.Mask" "F.Paste")
			(net "M_G_CPU0_SA_CA<1>")
		)
		(pad "212" smd rect
			(at 2.050034 -6.374892 90)
			(size 0.519938 1.4986)
			(layers "F.Cu" "F.Mask" "F.Paste")
			(net "GND")
		)
		(pad "213" smd rect
			(at 2.050034 -5.525008 90)
			(size 0.519938 1.4986)
			(layers "F.Cu" "F.Mask" "F.Paste")
			(net "M_G_CPU0_SA_CA<3>")
		)
		(pad "214" smd rect
			(at 2.050034 -4.675124 90)
			(size 0.519938 1.4986)
			(layers "F.Cu" "F.Mask" "F.Paste")
			(net "GND")
		)
		(pad "215" smd rect
			(at 2.050034 -3.824986 90)
			(size 0.519938 1.4986)
			(layers "F.Cu" "F.Mask" "F.Paste")
			(net "M_G_CPU0_SA_CA<5>")
		)
		(pad "216" smd rect
			(at 2.050034 -2.975102 90)
			(size 0.519938 1.4986)
			(layers "F.Cu" "F.Mask" "F.Paste")
			(net "GND")
		)
		(pad "217" smd rect
			(at 2.050034 -2.124964 90)
			(size 0.519938 1.4986)
			(layers "F.Cu" "F.Mask" "F.Paste")
			(net "M_G_CPU0_CLK_DP<0>")
		)
		(pad "218" smd rect
			(at 2.050034 -1.27508 90)
			(size 0.519938 1.4986)
			(layers "F.Cu" "F.Mask" "F.Paste")
			(net "M_G_CPU0_CLK_DN<0>")
		)
		(pad "219" smd rect
			(at 2.050034 -0.424942 90)
			(size 0.519938 1.4986)
			(layers "F.Cu" "F.Mask" "F.Paste")
			(net "GND")
		)
		(pad "220" smd rect
			(at 2.050034 5.525008 90)
			(size 0.519938 1.4986)
			(layers "F.Cu" "F.Mask" "F.Paste")
			(net "Net_2337")
		)
		(pad "221" smd rect
			(at 2.050034 6.374892 90)
			(size 0.519938 1.4986)
			(layers "F.Cu" "F.Mask" "F.Paste")
			(net "M_G_CPU0_SB_CA<1>")
		)
		(pad "222" smd rect
			(at 2.050034 7.22503 90)
			(size 0.519938 1.4986)
			(layers "F.Cu" "F.Mask" "F.Paste")
			(net "GND")
		)
		(pad "223" smd rect
			(at 2.050034 8.074914 90)
			(size 0.519938 1.4986)
			(layers "F.Cu" "F.Mask" "F.Paste")
			(net "M_G_CPU0_SB_CA<3>")
		)
		(pad "224" smd rect
			(at 2.050034 8.925052 90)
			(size 0.519938 1.4986)
			(layers "F.Cu" "F.Mask" "F.Paste")
			(net "GND")
		)
		(pad "225" smd rect
			(at 2.050034 9.774936 90)
			(size 0.519938 1.4986)
			(layers "F.Cu" "F.Mask" "F.Paste")
			(net "M_G_CPU0_SB_CA<5>")
		)
		(pad "226" smd rect
			(at 2.050034 10.625074 90)
			(size 0.519938 1.4986)
			(layers "F.Cu" "F.Mask" "F.Paste")
			(net "GND")
		)
		(pad "227" smd rect
			(at 2.050034 11.474958 90)
			(size 0.519938 1.4986)
			(layers "F.Cu" "F.Mask" "F.Paste")
			(net "M_G_CPU0_SB_PAR")
		)
		(pad "228" smd rect
			(at 2.050034 12.325096 90)
			(size 0.519938 1.4986)
			(layers "F.Cu" "F.Mask" "F.Paste")
			(net "GND")
		)
		(pad "229" smd rect
			(at 2.050034 13.17498 90)
			(size 0.519938 1.4986)
			(layers "F.Cu" "F.Mask" "F.Paste")
			(net "M_G_CPU0_SB_CS_N<1>")
		)
		(pad "230" smd rect
			(at 2.050034 14.025118 90)
			(size 0.519938 1.4986)
			(layers "F.Cu" "F.Mask" "F.Paste")
			(net "GND")
		)
	)
)
